(kicad_pcb
	(version 20211014)
	(generator pcbnew)
	(general
    (thickness 1.6)
  )
	(paper "A4")
	(title_block
    (title "SA800U (Snapdragon 845) Baseboard")
    (date "2023-10-19")
    (rev "1.0.3")
    (company "Antmicro Ltd.")
    (comment 1 "www.antmicro.com")
		(comment 9 "footprints 565-579 of 589")
	)
	(layers
    (0 "F.Cu" signal)
    (1 "In1.Cu" power)
    (2 "In2.Cu" signal)
    (3 "In3.Cu" signal)
    (4 "In4.Cu" power)
    (31 "B.Cu" signal)
    (32 "B.Adhes" user "B.Adhesive")
    (33 "F.Adhes" user "F.Adhesive")
    (34 "B.Paste" user)
    (35 "F.Paste" user)
    (36 "B.SilkS" user "B.Silkscreen")
    (37 "F.SilkS" user "F.Silkscreen")
    (38 "B.Mask" user)
    (39 "F.Mask" user)
    (40 "Dwgs.User" user "User.Drawings")
    (41 "Cmts.User" user "User.Comments")
    (42 "Eco1.User" user "User.Eco1")
    (43 "Eco2.User" user "User.Eco2")
    (44 "Edge.Cuts" user)
    (45 "Margin" user)
    (46 "B.CrtYd" user "B.Courtyard")
    (47 "F.CrtYd" user "F.Courtyard")
    (48 "B.Fab" user)
    (49 "F.Fab" user)
  )
	(footprint "sa800u-baseboard-hw-footprints:TP_SMD_0.75mm" (layer "B.Cu")
    (tedit 5E4A9375)
    (at 91 137.8)
    (property "Author" "Antmicro")
    (property "License" "Apache-2.0")
    (property "MPN" "")
    (property "Manufacturer" "")
    (property "Sheetfile" "usb-pd.kicad_sch")
    (property "Sheetname" "USB-PD")
    (attr smd)
    (fp_text reference "TP97" (at 1.44 1.24 180) (layer "B.SilkS")
      (effects (font (size 0.7 0.7) (thickness 0.15)) (justify left bottom mirror))
    )
    (fp_text value "TP_0.75mm_SMD" (at 0 -1.2 180) (layer "B.Fab")
      (effects (font (size 0.7 0.7) (thickness 0.15)) (justify left bottom mirror))
    )
    (fp_text user "License: Apache-2.0" (at -0.4 -5.101 180) (layer "B.Fab") hide
      (effects (font (size 0.7 0.7) (thickness 0.15)) (justify left bottom mirror))
    )
    (fp_text user "Author: Antmicro" (at -0.4 -3.901 180) (layer "B.Fab") hide
      (effects (font (size 0.7 0.7) (thickness 0.15)) (justify left bottom mirror))
    )
    (fp_text user "${REFERENCE}" (at -0.4 -2.7 180) (layer "B.Fab") hide
      (effects (font (size 0.7 0.7) (thickness 0.15)) (justify left bottom mirror))
    )
    (pad "1" smd circle (at 0 0) (size 0.75 0.75) (layers "B.Cu" "B.Mask")
      (net 107 "/USB-PD/PD_VBUS") (pinfunction "1") (pintype "passive"))
  )
	(footprint "sa800u-baseboard-hw-footprints:TP_SMD_0.75mm" (layer "B.Cu")
    (tedit 5E4A9375)
    (at 74.4 147.4)
    (property "Author" "Antmicro")
    (property "License" "Apache-2.0")
    (property "MPN" "")
    (property "Manufacturer" "")
    (property "Sheetfile" "usb-pd.kicad_sch")
    (property "Sheetname" "USB-PD")
    (attr smd)
    (fp_text reference "TP98" (at 0.78 1.28 180) (layer "B.SilkS")
      (effects (font (size 0.7 0.7) (thickness 0.15)) (justify left bottom mirror))
    )
    (fp_text value "TP_0.75mm_SMD" (at 0 -1.2 180) (layer "B.Fab")
      (effects (font (size 0.7 0.7) (thickness 0.15)) (justify left bottom mirror))
    )
    (fp_text user "License: Apache-2.0" (at -0.4 -5.101 180) (layer "B.Fab") hide
      (effects (font (size 0.7 0.7) (thickness 0.15)) (justify left bottom mirror))
    )
    (fp_text user "${REFERENCE}" (at -0.4 -2.7 180) (layer "B.Fab") hide
      (effects (font (size 0.7 0.7) (thickness 0.15)) (justify left bottom mirror))
    )
    (fp_text user "Author: Antmicro" (at -0.4 -3.901 180) (layer "B.Fab") hide
      (effects (font (size 0.7 0.7) (thickness 0.15)) (justify left bottom mirror))
    )
    (pad "1" smd circle (at 0 0) (size 0.75 0.75) (layers "B.Cu" "B.Mask")
      (net 1 "GND") (pinfunction "1") (pintype "passive"))
  )
	(footprint "sa800u-baseboard-hw-footprints:TP_SMD_0.75mm" (layer "B.Cu")
    (tedit 5E4A9375)
    (at 80.05 126.95)
    (property "Author" "Antmicro")
    (property "License" "Apache-2.0")
    (property "MPN" "")
    (property "Manufacturer" "")
    (property "Sheetfile" "psu.kicad_sch")
    (property "Sheetname" "PSU")
    (attr smd)
    (fp_text reference "TP48" (at 1.59 1.23 180) (layer "B.SilkS")
      (effects (font (size 0.7 0.7) (thickness 0.15)) (justify left bottom mirror))
    )
    (fp_text value "TP_0.75mm_SMD" (at 0 -1.2 180) (layer "B.Fab")
      (effects (font (size 0.7 0.7) (thickness 0.15)) (justify left bottom mirror))
    )
    (fp_text user "${REFERENCE}" (at -0.4 -2.7 180) (layer "B.Fab") hide
      (effects (font (size 0.7 0.7) (thickness 0.15)) (justify left bottom mirror))
    )
    (fp_text user "Author: Antmicro" (at -0.4 -3.901 180) (layer "B.Fab") hide
      (effects (font (size 0.7 0.7) (thickness 0.15)) (justify left bottom mirror))
    )
    (fp_text user "License: Apache-2.0" (at -0.4 -5.101 180) (layer "B.Fab") hide
      (effects (font (size 0.7 0.7) (thickness 0.15)) (justify left bottom mirror))
    )
    (pad "1" smd circle (at 0 0) (size 0.75 0.75) (layers "B.Cu" "B.Mask")
      (net 152 "/PSU/AUX_VDD") (pinfunction "1") (pintype "passive"))
  )
	(footprint "sa800u-baseboard-hw-footprints:TP_SMD_0.75mm" (layer "B.Cu")
    (tedit 5E4A9375)
    (at 80.05 125.2)
    (property "Author" "Antmicro")
    (property "License" "Apache-2.0")
    (property "MPN" "")
    (property "Manufacturer" "")
    (property "Sheetfile" "psu.kicad_sch")
    (property "Sheetname" "PSU")
    (attr smd)
    (fp_text reference "TP49" (at 1.57 1.24 180) (layer "B.SilkS")
      (effects (font (size 0.7 0.7) (thickness 0.15)) (justify left bottom mirror))
    )
    (fp_text value "TP_0.75mm_SMD" (at 0 -1.2 180) (layer "B.Fab")
      (effects (font (size 0.7 0.7) (thickness 0.15)) (justify left bottom mirror))
    )
    (fp_text user "License: Apache-2.0" (at -0.4 -5.101 180) (layer "B.Fab") hide
      (effects (font (size 0.7 0.7) (thickness 0.15)) (justify left bottom mirror))
    )
    (fp_text user "${REFERENCE}" (at -0.4 -2.7 180) (layer "B.Fab") hide
      (effects (font (size 0.7 0.7) (thickness 0.15)) (justify left bottom mirror))
    )
    (fp_text user "Author: Antmicro" (at -0.4 -3.901 180) (layer "B.Fab") hide
      (effects (font (size 0.7 0.7) (thickness 0.15)) (justify left bottom mirror))
    )
    (pad "1" smd circle (at 0 0) (size 0.75 0.75) (layers "B.Cu" "B.Mask")
      (net 142 "PD_VDD") (pinfunction "1") (pintype "passive"))
  )
	(footprint "sa800u-baseboard-hw-footprints:TP_SMD_0.75mm" (layer "B.Cu")
    (tedit 5E4A9375)
    (at 80.05 123.5492)
    (property "Author" "Antmicro")
    (property "License" "Apache-2.0")
    (property "MPN" "")
    (property "Manufacturer" "")
    (property "Sheetfile" "psu.kicad_sch")
    (property "Sheetname" "PSU")
    (attr smd)
    (fp_text reference "TP50" (at 1.59 1.2 180) (layer "B.SilkS")
      (effects (font (size 0.7 0.7) (thickness 0.15)) (justify left bottom mirror))
    )
    (fp_text value "TP_0.75mm_SMD" (at 0 -1.2 180) (layer "B.Fab")
      (effects (font (size 0.7 0.7) (thickness 0.15)) (justify left bottom mirror))
    )
    (fp_text user "Author: Antmicro" (at -0.4 -3.901 180) (layer "B.Fab") hide
      (effects (font (size 0.7 0.7) (thickness 0.15)) (justify left bottom mirror))
    )
    (fp_text user "License: Apache-2.0" (at -0.4 -5.101 180) (layer "B.Fab") hide
      (effects (font (size 0.7 0.7) (thickness 0.15)) (justify left bottom mirror))
    )
    (fp_text user "${REFERENCE}" (at -0.4 -2.7 180) (layer "B.Fab") hide
      (effects (font (size 0.7 0.7) (thickness 0.15)) (justify left bottom mirror))
    )
    (pad "1" smd circle (at 0 0) (size 0.75 0.75) (layers "B.Cu" "B.Mask")
      (net 136 "5V_POE") (pinfunction "1") (pintype "passive"))
  )
	(footprint "sa800u-baseboard-hw-footprints:TP_SMD_0.75mm" (layer "B.Cu")
    (tedit 5E4A9375)
    (at 70.7492 126.6 90)
    (property "Author" "Antmicro")
    (property "License" "Apache-2.0")
    (property "MPN" "")
    (property "Manufacturer" "")
    (property "Sheetfile" "psu.kicad_sch")
    (property "Sheetname" "PSU")
    (attr smd)
    (fp_text reference "TP51" (at -1.22 1.7808) (layer "B.SilkS")
      (effects (font (size 0.7 0.7) (thickness 0.15)) (justify left bottom mirror))
    )
    (fp_text value "TP_0.75mm_SMD" (at 0 -1.2 270) (layer "B.Fab")
      (effects (font (size 0.7 0.7) (thickness 0.15)) (justify left bottom mirror))
    )
    (fp_text user "License: Apache-2.0" (at -0.4 -5.101 270) (layer "B.Fab") hide
      (effects (font (size 0.7 0.7) (thickness 0.15)) (justify left bottom mirror))
    )
    (fp_text user "Author: Antmicro" (at -0.4 -3.901 270) (layer "B.Fab") hide
      (effects (font (size 0.7 0.7) (thickness 0.15)) (justify left bottom mirror))
    )
    (fp_text user "${REFERENCE}" (at -0.4 -2.7 270) (layer "B.Fab") hide
      (effects (font (size 0.7 0.7) (thickness 0.15)) (justify left bottom mirror))
    )
    (pad "1" smd circle (at 0 0 90) (size 0.75 0.75) (layers "B.Cu" "B.Mask")
      (net 354 "/PSU/G1") (pinfunction "1") (pintype "passive"))
  )
	(footprint "sa800u-baseboard-hw-footprints:TP_SMD_0.75mm" (layer "B.Cu")
    (tedit 5E4A9375)
    (at 70.8 125 90)
    (property "Author" "Antmicro")
    (property "License" "Apache-2.0")
    (property "MPN" "")
    (property "Manufacturer" "")
    (property "Sheetfile" "psu.kicad_sch")
    (property "Sheetname" "PSU")
    (attr smd)
    (fp_text reference "TP52" (at 0.49 1.77) (layer "B.SilkS")
      (effects (font (size 0.7 0.7) (thickness 0.15)) (justify left bottom mirror))
    )
    (fp_text value "TP_0.75mm_SMD" (at 0 -1.2 270) (layer "B.Fab")
      (effects (font (size 0.7 0.7) (thickness 0.15)) (justify left bottom mirror))
    )
    (fp_text user "Author: Antmicro" (at -0.4 -3.901 270) (layer "B.Fab") hide
      (effects (font (size 0.7 0.7) (thickness 0.15)) (justify left bottom mirror))
    )
    (fp_text user "${REFERENCE}" (at -0.4 -2.7 270) (layer "B.Fab") hide
      (effects (font (size 0.7 0.7) (thickness 0.15)) (justify left bottom mirror))
    )
    (fp_text user "License: Apache-2.0" (at -0.4 -5.101 270) (layer "B.Fab") hide
      (effects (font (size 0.7 0.7) (thickness 0.15)) (justify left bottom mirror))
    )
    (pad "1" smd circle (at 0 0 90) (size 0.75 0.75) (layers "B.Cu" "B.Mask")
      (net 355 "/PSU/G2") (pinfunction "1") (pintype "passive"))
  )
	(footprint "sa800u-baseboard-hw-footprints:TP_SMD_0.75mm" (layer "B.Cu")
    (tedit 5E4A9375)
    (at 70.7492 123.2 90)
    (property "Author" "Antmicro")
    (property "License" "Apache-2.0")
    (property "MPN" "")
    (property "Manufacturer" "")
    (property "Sheetfile" "psu.kicad_sch")
    (property "Sheetname" "PSU")
    (attr smd)
    (fp_text reference "TP53" (at 0.55 1.8108) (layer "B.SilkS")
      (effects (font (size 0.7 0.7) (thickness 0.15)) (justify left bottom mirror))
    )
    (fp_text value "TP_0.75mm_SMD" (at 0 -1.2 270) (layer "B.Fab")
      (effects (font (size 0.7 0.7) (thickness 0.15)) (justify left bottom mirror))
    )
    (fp_text user "License: Apache-2.0" (at -0.4 -5.101 270) (layer "B.Fab") hide
      (effects (font (size 0.7 0.7) (thickness 0.15)) (justify left bottom mirror))
    )
    (fp_text user "${REFERENCE}" (at -0.4 -2.7 270) (layer "B.Fab") hide
      (effects (font (size 0.7 0.7) (thickness 0.15)) (justify left bottom mirror))
    )
    (fp_text user "Author: Antmicro" (at -0.4 -3.901 270) (layer "B.Fab") hide
      (effects (font (size 0.7 0.7) (thickness 0.15)) (justify left bottom mirror))
    )
    (pad "1" smd circle (at 0 0 90) (size 0.75 0.75) (layers "B.Cu" "B.Mask")
      (net 367 "/PSU/G3") (pinfunction "1") (pintype "passive"))
  )
	(footprint "sa800u-baseboard-hw-footprints:TP_SMD_0.75mm" (layer "B.Cu")
    (tedit 5E4A9375)
    (at 88.2 137.8)
    (property "Author" "Antmicro")
    (property "License" "Apache-2.0")
    (property "MPN" "")
    (property "Manufacturer" "")
    (property "Sheetfile" "usb-pd.kicad_sch")
    (property "Sheetname" "USB-PD")
    (attr smd)
    (fp_text reference "TP92" (at 1.28 1.23 180) (layer "B.SilkS")
      (effects (font (size 0.7 0.7) (thickness 0.15)) (justify left bottom mirror))
    )
    (fp_text value "TP_0.75mm_SMD" (at 0 -1.2 180) (layer "B.Fab")
      (effects (font (size 0.7 0.7) (thickness 0.15)) (justify left bottom mirror))
    )
    (fp_text user "License: Apache-2.0" (at -0.4 -5.101 180) (layer "B.Fab") hide
      (effects (font (size 0.7 0.7) (thickness 0.15)) (justify left bottom mirror))
    )
    (fp_text user "${REFERENCE}" (at -0.4 -2.7 180) (layer "B.Fab") hide
      (effects (font (size 0.7 0.7) (thickness 0.15)) (justify left bottom mirror))
    )
    (fp_text user "Author: Antmicro" (at -0.4 -3.901 180) (layer "B.Fab") hide
      (effects (font (size 0.7 0.7) (thickness 0.15)) (justify left bottom mirror))
    )
    (pad "1" smd circle (at 0 0) (size 0.75 0.75) (layers "B.Cu" "B.Mask")
      (net 140 "/USB-PD/VREG_1V2") (pinfunction "1") (pintype "passive"))
  )
	(footprint "sa800u-baseboard-hw-footprints:TP_SMD_0.75mm" (layer "B.Cu")
    (tedit 5E4A9375)
    (at 90 119.2)
    (property "Author" "Antmicro")
    (property "License" "Apache-2.0")
    (property "MPN" "")
    (property "Manufacturer" "")
    (property "Sheetfile" "psu.kicad_sch")
    (property "Sheetname" "PSU")
    (attr smd)
    (fp_text reference "TP73" (at 1.33 1.23 180) (layer "B.SilkS")
      (effects (font (size 0.7 0.7) (thickness 0.15)) (justify left bottom mirror))
    )
    (fp_text value "TP_0.75mm_SMD" (at 0 -1.2 180) (layer "B.Fab")
      (effects (font (size 0.7 0.7) (thickness 0.15)) (justify left bottom mirror))
    )
    (fp_text user "License: Apache-2.0" (at -0.4 -5.101 180) (layer "B.Fab") hide
      (effects (font (size 0.7 0.7) (thickness 0.15)) (justify left bottom mirror))
    )
    (fp_text user "${REFERENCE}" (at -0.4 -2.7 180) (layer "B.Fab") hide
      (effects (font (size 0.7 0.7) (thickness 0.15)) (justify left bottom mirror))
    )
    (fp_text user "Author: Antmicro" (at -0.4 -3.901 180) (layer "B.Fab") hide
      (effects (font (size 0.7 0.7) (thickness 0.15)) (justify left bottom mirror))
    )
    (pad "1" smd circle (at 0 0) (size 0.75 0.75) (layers "B.Cu" "B.Mask")
      (net 133 "5V_SYS") (pinfunction "1") (pintype "passive"))
  )
	(footprint "sa800u-baseboard-hw-footprints:TP_SMD_0.75mm" (layer "B.Cu")
    (tedit 5E4A9375)
    (at 87.6 119.2)
    (property "Author" "Antmicro")
    (property "License" "Apache-2.0")
    (property "MPN" "")
    (property "Manufacturer" "")
    (property "Sheetfile" "psu.kicad_sch")
    (property "Sheetname" "PSU")
    (attr smd)
    (fp_text reference "TP68" (at 1.23 -0.46 180) (layer "B.SilkS")
      (effects (font (size 0.7 0.7) (thickness 0.15)) (justify left bottom mirror))
    )
    (fp_text value "TP_0.75mm_SMD" (at 0 -1.2 180) (layer "B.Fab")
      (effects (font (size 0.7 0.7) (thickness 0.15)) (justify left bottom mirror))
    )
    (fp_text user "License: Apache-2.0" (at -0.4 -5.101 180) (layer "B.Fab") hide
      (effects (font (size 0.7 0.7) (thickness 0.15)) (justify left bottom mirror))
    )
    (fp_text user "Author: Antmicro" (at -0.4 -3.901 180) (layer "B.Fab") hide
      (effects (font (size 0.7 0.7) (thickness 0.15)) (justify left bottom mirror))
    )
    (fp_text user "${REFERENCE}" (at -0.4 -2.7 180) (layer "B.Fab") hide
      (effects (font (size 0.7 0.7) (thickness 0.15)) (justify left bottom mirror))
    )
    (pad "1" smd circle (at 0 0) (size 0.75 0.75) (layers "B.Cu" "B.Mask")
      (net 74 "VDD") (pinfunction "1") (pintype "passive"))
  )
	(footprint "sa800u-baseboard-hw-footprints:TP_SMD_0.75mm" (layer "B.Cu")
    (tedit 5E4A9375)
    (at 87.6 100.4)
    (property "Author" "Antmicro")
    (property "License" "Apache-2.0")
    (property "MPN" "")
    (property "Manufacturer" "")
    (property "Sheetfile" "psu.kicad_sch")
    (property "Sheetname" "PSU")
    (attr smd)
    (fp_text reference "TP61" (at 1.14 1.3 180) (layer "B.SilkS")
      (effects (font (size 0.7 0.7) (thickness 0.15)) (justify left bottom mirror))
    )
    (fp_text value "TP_0.75mm_SMD" (at 0 -1.2 180) (layer "B.Fab")
      (effects (font (size 0.7 0.7) (thickness 0.15)) (justify left bottom mirror))
    )
    (fp_text user "Author: Antmicro" (at -0.4 -3.901 180) (layer "B.Fab") hide
      (effects (font (size 0.7 0.7) (thickness 0.15)) (justify left bottom mirror))
    )
    (fp_text user "${REFERENCE}" (at -0.4 -2.7 180) (layer "B.Fab") hide
      (effects (font (size 0.7 0.7) (thickness 0.15)) (justify left bottom mirror))
    )
    (fp_text user "License: Apache-2.0" (at -0.4 -5.101 180) (layer "B.Fab") hide
      (effects (font (size 0.7 0.7) (thickness 0.15)) (justify left bottom mirror))
    )
    (pad "1" smd circle (at 0 0) (size 0.75 0.75) (layers "B.Cu" "B.Mask")
      (net 74 "VDD") (pinfunction "1") (pintype "passive"))
  )
	(footprint "sa800u-baseboard-hw-footprints:TP_SMD_0.75mm" (layer "B.Cu")
    (tedit 5E4A9375)
    (at 90.1 100.4)
    (property "Author" "Antmicro")
    (property "License" "Apache-2.0")
    (property "MPN" "")
    (property "Manufacturer" "")
    (property "Sheetfile" "psu.kicad_sch")
    (property "Sheetname" "PSU")
    (attr smd)
    (fp_text reference "TP70" (at 1.38 1.3 180) (layer "B.SilkS")
      (effects (font (size 0.7 0.7) (thickness 0.15)) (justify left bottom mirror))
    )
    (fp_text value "TP_0.75mm_SMD" (at 0 -1.2 180) (layer "B.Fab")
      (effects (font (size 0.7 0.7) (thickness 0.15)) (justify left bottom mirror))
    )
    (fp_text user "${REFERENCE}" (at -0.4 -2.7 180) (layer "B.Fab") hide
      (effects (font (size 0.7 0.7) (thickness 0.15)) (justify left bottom mirror))
    )
    (fp_text user "Author: Antmicro" (at -0.4 -3.901 180) (layer "B.Fab") hide
      (effects (font (size 0.7 0.7) (thickness 0.15)) (justify left bottom mirror))
    )
    (fp_text user "License: Apache-2.0" (at -0.4 -5.101 180) (layer "B.Fab") hide
      (effects (font (size 0.7 0.7) (thickness 0.15)) (justify left bottom mirror))
    )
    (pad "1" smd circle (at 0 0) (size 0.75 0.75) (layers "B.Cu" "B.Mask")
      (net 137 "3V8_SYS") (pinfunction "1") (pintype "passive"))
  )
	(footprint "sa800u-baseboard-hw-footprints:TP_SMD_0.75mm" (layer "B.Cu")
    (tedit 5E4A9375)
    (at 85.1 100.4)
    (property "Author" "Antmicro")
    (property "License" "Apache-2.0")
    (property "MPN" "")
    (property "Manufacturer" "")
    (property "Sheetfile" "psu.kicad_sch")
    (property "Sheetname" "PSU")
    (attr smd)
    (fp_text reference "TP74" (at 0.85 1.32 180) (layer "B.SilkS")
      (effects (font (size 0.7 0.7) (thickness 0.15)) (justify left bottom mirror))
    )
    (fp_text value "TP_0.75mm_SMD" (at 0 -1.2 180) (layer "B.Fab")
      (effects (font (size 0.7 0.7) (thickness 0.15)) (justify left bottom mirror))
    )
    (fp_text user "Author: Antmicro" (at -0.4 -3.901 180) (layer "B.Fab") hide
      (effects (font (size 0.7 0.7) (thickness 0.15)) (justify left bottom mirror))
    )
    (fp_text user "License: Apache-2.0" (at -0.4 -5.101 180) (layer "B.Fab") hide
      (effects (font (size 0.7 0.7) (thickness 0.15)) (justify left bottom mirror))
    )
    (fp_text user "${REFERENCE}" (at -0.4 -2.7 180) (layer "B.Fab") hide
      (effects (font (size 0.7 0.7) (thickness 0.15)) (justify left bottom mirror))
    )
    (pad "1" smd circle (at 0 0) (size 0.75 0.75) (layers "B.Cu" "B.Mask")
      (net 1 "GND") (pinfunction "1") (pintype "passive"))
  )
	(footprint "sa800u-baseboard-hw-footprints:TP_SMD_0.75mm" (layer "B.Cu")
    (tedit 5E4A9375)
    (at 119.5 106.3)
    (property "Author" "Antmicro")
    (property "License" "Apache-2.0")
    (property "MPN" "")
    (property "Manufacturer" "")
    (property "Sheetfile" "camera-interface.kicad_sch")
    (property "Sheetname" "Camera Interface")
    (attr smd)
    (fp_text reference "TP28" (at -0.31 0.39 180) (layer "B.SilkS")
      (effects (font (size 0.7 0.7) (thickness 0.15)) (justify left bottom mirror))
    )
    (fp_text value "TP_0.75mm_SMD" (at 0 -1.2 180) (layer "B.Fab")
      (effects (font (size 0.7 0.7) (thickness 0.15)) (justify left bottom mirror))
    )
    (fp_text user "License: Apache-2.0" (at -0.4 -5.101 180) (layer "B.Fab") hide
      (effects (font (size 0.7 0.7) (thickness 0.15)) (justify left bottom mirror))
    )
    (fp_text user "${REFERENCE}" (at -0.4 -2.7 180) (layer "B.Fab") hide
      (effects (font (size 0.7 0.7) (thickness 0.15)) (justify left bottom mirror))
    )
    (fp_text user "Author: Antmicro" (at -0.4 -3.901 180) (layer "B.Fab") hide
      (effects (font (size 0.7 0.7) (thickness 0.15)) (justify left bottom mirror))
    )
    (pad "1" smd circle (at 0 0) (size 0.75 0.75) (layers "B.Cu" "B.Mask")
      (net 133 "5V_SYS") (pinfunction "1") (pintype "passive"))
  )
)
